FILE_TYPE = MACRO_DRAWING;
SET COLOR_WIRE YELLOW;
SET COLOR_PROP ORANGE;
SET COLOR_DOT WHITE;
SET COLOR_ARC YELLOW;
SET COLOR_BODY GREEN;
SET COLOR_NOTE PURPLE;
SET PROP_DISPLAY VALUE;
SET PAGE_NUMBER P42;
SET PATH_NUMBER P67;
FORCEADD OFFPAGE..2
(10250 1450);
FORCEPROP 2 LAST $XR0 15 
J 0
(10439 1450);
DISPLAY 0.638298 (10439 1450);
PAINT MONO (10439 1450);
FORCEPROP 2 LAST $XR1 36 
J 0
(10529 1450);
DISPLAY 0.638298 (10529 1450);
PAINT MONO (10529 1450);
FORCEPROP 2 LAST PATH I12
J 0
(10550 1500);
DISPLAY 0.680851 (10550 1500);
DISPLAY INVISIBLE (10550 1500);
FORCEPROP 1 LAST COMMENT_BODY TRUE
J 0
(10205 1355);
DISPLAY 0.872340 (10205 1355);
PAINT PEACH (10205 1355);
DISPLAY INVISIBLE (10205 1355);
FORCEPROP 1 LAST OFFPAGE TRUE
J 0
(10575 1325);
DISPLAY 0.872340 (10575 1325);
PAINT GREEN (10575 1325);
DISPLAY INVISIBLE (10575 1325);
FORCEPROP 2 LAST CDS_LIB standard
J 0
(10250 1450);
DISPLAY INVISIBLE (10250 1450);
FORCEADD Q_RES..1
(8500 1450);
FORCEPROP 1 LAST VALUE 4.7K
J 2
(8375 1450);
DISPLAY 0.510638 (8375 1450);
PAINT SKYBLUE (8375 1450);
FORCEPROP 1 LAST MATERIAL CHIP
J 0
(8625 1450);
DISPLAY 0.510638 (8625 1450);
PAINT SKYBLUE (8625 1450);
FORCEPROP 1 LAST PACK_TYPE 0402LF
J 0
(8750 1300);
DISPLAY 0.510638 (8750 1300);
PAINT SKYBLUE (8750 1300);
DISPLAY INVISIBLE (8750 1300);
FORCEPROP 1 LAST WATTAGE 1/16W
J 2
(8475 1300);
DISPLAY 0.510638 (8475 1300);
PAINT SKYBLUE (8475 1300);
DISPLAY INVISIBLE (8475 1300);
FORCEPROP 1 LAST PATH I13
J 0
(8450 1600);
DISPLAY 0.978723 (8450 1600);
PAINT WHITE (8450 1600);
DISPLAY INVISIBLE (8450 1600);
FORCEPROP 1 LAST TOLERANCE 1%
J 0
(8500 1350);
DISPLAY 0.510638 (8500 1350);
PAINT SKYBLUE (8500 1350);
DISPLAY INVISIBLE (8500 1350);
FORCEPROP 2 LAST CDS_LIB pure_quanta
J 0
(8500 1450);
DISPLAY INVISIBLE (8500 1450);
FORCEPROP 1 LAST PART_NUMBER CS24702FB06
J 0
(8450 1550);
DISPLAY 0.510638 (8450 1550);
PAINT WHITE (8450 1550);
DISPLAY INVISIBLE (8450 1550);
FORCEPROP 1 LAST LOCATION R621
J 0
(8150 1450);
DISPLAY 0.702128 (8150 1450);
PAINT YELLOW (8150 1450);
FORCEPROP 0 LAST $SEC 1
J 0
(8225 1500);
DISPLAY INVISIBLE (8225 1500);
FORCEPROP 0 LAST CDS_SEC 1
J 0
(8225 1500);
DISPLAY INVISIBLE (8225 1500);
FORCEPROP 1 LASTPIN (8400 1450) $PN 1
J 0
(8412 1462);
DISPLAY 0.808511 (8412 1462);
PAINT WHITE (8412 1462);
DISPLAY INVISIBLE (8412 1462);
FORCEPROP 1 LASTPIN (8600 1450) $PN 2
J 0
(8562 1462);
DISPLAY 0.808511 (8562 1462);
PAINT WHITE (8562 1462);
DISPLAY INVISIBLE (8562 1462);
FORCEADD OFFPAGE..2
(10250 2500);
FORCEPROP 2 LAST $XR0 35 
J 0
(10439 2500);
DISPLAY 0.638298 (10439 2500);
PAINT MONO (10439 2500);
FORCEPROP 2 LAST PATH I26
J 0
(10550 2550);
DISPLAY 0.680851 (10550 2550);
DISPLAY INVISIBLE (10550 2550);
FORCEPROP 1 LAST COMMENT_BODY TRUE
J 0
(10205 2405);
DISPLAY 0.872340 (10205 2405);
PAINT PEACH (10205 2405);
DISPLAY INVISIBLE (10205 2405);
FORCEPROP 1 LAST OFFPAGE TRUE
J 0
(10575 2375);
DISPLAY 0.872340 (10575 2375);
PAINT GREEN (10575 2375);
DISPLAY INVISIBLE (10575 2375);
FORCEPROP 2 LAST CDS_LIB standard
J 0
(10250 2500);
DISPLAY INVISIBLE (10250 2500);
FORCEADD Q_RES..1
(8500 2500);
FORCEPROP 1 LAST VALUE 4.7K
J 2
(8375 2500);
DISPLAY 0.510638 (8375 2500);
PAINT SKYBLUE (8375 2500);
FORCEPROP 1 LAST MATERIAL CHIP
J 0
(8625 2500);
DISPLAY 0.510638 (8625 2500);
PAINT SKYBLUE (8625 2500);
FORCEPROP 1 LAST PACK_TYPE 0402LF
J 0
(8750 2350);
DISPLAY 0.510638 (8750 2350);
PAINT SKYBLUE (8750 2350);
DISPLAY INVISIBLE (8750 2350);
FORCEPROP 1 LAST WATTAGE 1/16W
J 2
(8475 2350);
DISPLAY 0.510638 (8475 2350);
PAINT SKYBLUE (8475 2350);
DISPLAY INVISIBLE (8475 2350);
FORCEPROP 1 LAST PATH I27
J 0
(8450 2650);
DISPLAY 0.978723 (8450 2650);
PAINT WHITE (8450 2650);
DISPLAY INVISIBLE (8450 2650);
FORCEPROP 1 LAST TOLERANCE 1%
J 0
(8500 2400);
DISPLAY 0.510638 (8500 2400);
PAINT SKYBLUE (8500 2400);
DISPLAY INVISIBLE (8500 2400);
FORCEPROP 2 LAST CDS_LIB pure_quanta
J 0
(8500 2500);
DISPLAY INVISIBLE (8500 2500);
FORCEPROP 1 LAST PART_NUMBER CS24702FB06
J 0
(8450 2600);
DISPLAY 0.510638 (8450 2600);
PAINT WHITE (8450 2600);
DISPLAY INVISIBLE (8450 2600);
FORCEPROP 1 LAST LOCATION R608
J 0
(8150 2500);
DISPLAY 0.702128 (8150 2500);
PAINT YELLOW (8150 2500);
FORCEPROP 0 LAST $SEC 1
J 0
(8225 2550);
DISPLAY INVISIBLE (8225 2550);
FORCEPROP 0 LAST CDS_SEC 1
J 0
(8225 2550);
DISPLAY INVISIBLE (8225 2550);
FORCEPROP 1 LASTPIN (8400 2500) $PN 1
J 0
(8412 2512);
DISPLAY 0.808511 (8412 2512);
PAINT WHITE (8412 2512);
DISPLAY INVISIBLE (8412 2512);
FORCEPROP 1 LASTPIN (8600 2500) $PN 2
J 0
(8562 2512);
DISPLAY 0.808511 (8562 2512);
PAINT WHITE (8562 2512);
DISPLAY INVISIBLE (8562 2512);
FORCEADD OFFPAGE..2
(10250 2650);
FORCEPROP 2 LAST $XR0 35 
J 0
(10439 2650);
DISPLAY 0.638298 (10439 2650);
PAINT MONO (10439 2650);
FORCEPROP 2 LAST PATH I28
J 0
(10550 2700);
DISPLAY 0.680851 (10550 2700);
DISPLAY INVISIBLE (10550 2700);
FORCEPROP 1 LAST COMMENT_BODY TRUE
J 0
(10205 2555);
DISPLAY 0.872340 (10205 2555);
PAINT PEACH (10205 2555);
DISPLAY INVISIBLE (10205 2555);
FORCEPROP 1 LAST OFFPAGE TRUE
J 0
(10575 2525);
DISPLAY 0.872340 (10575 2525);
PAINT GREEN (10575 2525);
DISPLAY INVISIBLE (10575 2525);
FORCEPROP 2 LAST CDS_LIB standard
J 0
(10250 2650);
DISPLAY INVISIBLE (10250 2650);
FORCEADD Q_RES..1
(8500 2650);
FORCEPROP 1 LAST MATERIAL CHIP
J 0
(8625 2650);
DISPLAY 0.510638 (8625 2650);
PAINT SKYBLUE (8625 2650);
FORCEPROP 1 LAST VALUE 4.7K
J 2
(8375 2650);
DISPLAY 0.510638 (8375 2650);
PAINT SKYBLUE (8375 2650);
FORCEPROP 1 LAST PACK_TYPE 0402LF
J 0
(8750 2500);
DISPLAY 0.510638 (8750 2500);
PAINT SKYBLUE (8750 2500);
DISPLAY INVISIBLE (8750 2500);
FORCEPROP 1 LAST WATTAGE 1/16W
J 2
(8475 2500);
DISPLAY 0.510638 (8475 2500);
PAINT SKYBLUE (8475 2500);
DISPLAY INVISIBLE (8475 2500);
FORCEPROP 1 LAST PATH I29
J 0
(8450 2800);
DISPLAY 0.978723 (8450 2800);
PAINT WHITE (8450 2800);
DISPLAY INVISIBLE (8450 2800);
FORCEPROP 1 LAST TOLERANCE 1%
J 0
(8500 2550);
DISPLAY 0.510638 (8500 2550);
PAINT SKYBLUE (8500 2550);
DISPLAY INVISIBLE (8500 2550);
FORCEPROP 2 LAST CDS_LIB pure_quanta
J 0
(8500 2650);
DISPLAY INVISIBLE (8500 2650);
FORCEPROP 1 LAST PART_NUMBER CS24702FB06
J 0
(8450 2750);
DISPLAY 0.510638 (8450 2750);
PAINT WHITE (8450 2750);
DISPLAY INVISIBLE (8450 2750);
FORCEPROP 1 LAST LOCATION R607
J 0
(8150 2650);
DISPLAY 0.702128 (8150 2650);
PAINT YELLOW (8150 2650);
FORCEPROP 0 LAST $SEC 1
J 0
(8225 2700);
DISPLAY INVISIBLE (8225 2700);
FORCEPROP 0 LAST CDS_SEC 1
J 0
(8225 2700);
DISPLAY INVISIBLE (8225 2700);
FORCEPROP 1 LASTPIN (8400 2650) $PN 1
J 0
(8412 2662);
DISPLAY 0.808511 (8412 2662);
PAINT WHITE (8412 2662);
DISPLAY INVISIBLE (8412 2662);
FORCEPROP 1 LASTPIN (8600 2650) $PN 2
J 0
(8562 2662);
DISPLAY 0.808511 (8562 2662);
PAINT WHITE (8562 2662);
DISPLAY INVISIBLE (8562 2662);
FORCEADD UNIVERSAL_POWER..1
(8050 4450);
FORCEPROP 3 LASTPIN (8050 4400) SIG_NAME P3V3_AUX\g
J 0
(8060 4410);
DISPLAY 0.659574 (8060 4410);
PAINT MONO (8060 4410);
DISPLAY INVISIBLE (8060 4410);
FORCEPROP 1 LAST HDL_POWER P3V3_AUX
J 1
(8050 4500);
DISPLAY 0.702128 (8050 4500);
PAINT GREEN (8050 4500);
FORCEPROP 1 LAST PATH I3
J 0
(8100 4475);
DISPLAY 0.872340 (8100 4475);
PAINT AQUA (8100 4475);
DISPLAY INVISIBLE (8100 4475);
FORCEPROP 2 LAST CDS_LIB logical_power
J 0
(8050 4450);
DISPLAY INVISIBLE (8050 4450);
FORCEADD OFFPAGE..2
(10250 3250);
FORCEPROP 2 LAST $XR0 35 
J 0
(10439 3250);
DISPLAY 0.638298 (10439 3250);
PAINT MONO (10439 3250);
FORCEPROP 2 LAST PATH I36
J 0
(10550 3300);
DISPLAY 0.680851 (10550 3300);
DISPLAY INVISIBLE (10550 3300);
FORCEPROP 1 LAST COMMENT_BODY TRUE
J 0
(10205 3155);
DISPLAY 0.872340 (10205 3155);
PAINT PEACH (10205 3155);
DISPLAY INVISIBLE (10205 3155);
FORCEPROP 1 LAST OFFPAGE TRUE
J 0
(10575 3125);
DISPLAY 0.872340 (10575 3125);
PAINT GREEN (10575 3125);
DISPLAY INVISIBLE (10575 3125);
FORCEPROP 2 LAST CDS_LIB standard
J 0
(10250 3250);
DISPLAY INVISIBLE (10250 3250);
FORCEADD Q_RES..1
(8500 3250);
FORCEPROP 1 LAST VALUE 4.7K
J 2
(8375 3250);
DISPLAY 0.510638 (8375 3250);
PAINT SKYBLUE (8375 3250);
FORCEPROP 1 LAST MATERIAL EMPTY
J 0
(8625 3250);
DISPLAY 0.510638 (8625 3250);
PAINT RED (8625 3250);
FORCEPROP 1 LAST PACK_TYPE 0402LF
J 0
(8750 3100);
DISPLAY 0.510638 (8750 3100);
PAINT SKYBLUE (8750 3100);
DISPLAY INVISIBLE (8750 3100);
FORCEPROP 1 LAST WATTAGE 1/16W
J 2
(8475 3100);
DISPLAY 0.510638 (8475 3100);
PAINT SKYBLUE (8475 3100);
DISPLAY INVISIBLE (8475 3100);
FORCEPROP 1 LAST PATH I37
J 0
(8450 3400);
DISPLAY 0.978723 (8450 3400);
PAINT WHITE (8450 3400);
DISPLAY INVISIBLE (8450 3400);
FORCEPROP 1 LAST TOLERANCE 1%
J 0
(8500 3150);
DISPLAY 0.510638 (8500 3150);
PAINT SKYBLUE (8500 3150);
DISPLAY INVISIBLE (8500 3150);
FORCEPROP 2 LAST CDS_LIB pure_quanta
J 0
(8500 3250);
DISPLAY INVISIBLE (8500 3250);
FORCEPROP 1 LAST PART_NUMBER CS24702FB06
J 0
(8450 3350);
DISPLAY 0.510638 (8450 3350);
PAINT WHITE (8450 3350);
DISPLAY INVISIBLE (8450 3350);
FORCEPROP 1 LAST LOCATION R595
J 0
(8150 3250);
DISPLAY 0.702128 (8150 3250);
PAINT YELLOW (8150 3250);
FORCEPROP 0 LAST $SEC 1
J 0
(8225 3300);
DISPLAY INVISIBLE (8225 3300);
FORCEPROP 0 LAST CDS_SEC 1
J 0
(8225 3300);
DISPLAY INVISIBLE (8225 3300);
FORCEPROP 1 LASTPIN (8400 3250) $PN 1
J 0
(8412 3262);
DISPLAY 0.808511 (8412 3262);
PAINT WHITE (8412 3262);
DISPLAY INVISIBLE (8412 3262);
FORCEPROP 1 LASTPIN (8600 3250) $PN 2
J 0
(8562 3262);
DISPLAY 0.808511 (8562 3262);
PAINT WHITE (8562 3262);
DISPLAY INVISIBLE (8562 3262);
FORCEADD OFFPAGE..2
(10250 3400);
FORCEPROP 2 LAST $XR0 35 
J 0
(10439 3400);
DISPLAY 0.638298 (10439 3400);
PAINT MONO (10439 3400);
FORCEPROP 2 LAST PATH I38
J 0
(10550 3450);
DISPLAY 0.680851 (10550 3450);
DISPLAY INVISIBLE (10550 3450);
FORCEPROP 1 LAST COMMENT_BODY TRUE
J 0
(10205 3305);
DISPLAY 0.872340 (10205 3305);
PAINT PEACH (10205 3305);
DISPLAY INVISIBLE (10205 3305);
FORCEPROP 1 LAST OFFPAGE TRUE
J 0
(10575 3275);
DISPLAY 0.872340 (10575 3275);
PAINT GREEN (10575 3275);
DISPLAY INVISIBLE (10575 3275);
FORCEPROP 2 LAST CDS_LIB standard
J 0
(10250 3400);
DISPLAY INVISIBLE (10250 3400);
FORCEADD Q_RES..1
(8500 3400);
FORCEPROP 1 LAST MATERIAL EMPTY
J 0
(8625 3400);
DISPLAY 0.510638 (8625 3400);
PAINT RED (8625 3400);
FORCEPROP 1 LAST VALUE 4.7K
J 2
(8375 3400);
DISPLAY 0.510638 (8375 3400);
PAINT SKYBLUE (8375 3400);
FORCEPROP 1 LAST PACK_TYPE 0402LF
J 0
(8750 3250);
DISPLAY 0.510638 (8750 3250);
PAINT SKYBLUE (8750 3250);
DISPLAY INVISIBLE (8750 3250);
FORCEPROP 1 LAST WATTAGE 1/16W
J 2
(8475 3250);
DISPLAY 0.510638 (8475 3250);
PAINT SKYBLUE (8475 3250);
DISPLAY INVISIBLE (8475 3250);
FORCEPROP 1 LAST PATH I39
J 0
(8450 3550);
DISPLAY 0.978723 (8450 3550);
PAINT WHITE (8450 3550);
DISPLAY INVISIBLE (8450 3550);
FORCEPROP 1 LAST TOLERANCE 1%
J 0
(8500 3300);
DISPLAY 0.510638 (8500 3300);
PAINT SKYBLUE (8500 3300);
DISPLAY INVISIBLE (8500 3300);
FORCEPROP 2 LAST CDS_LIB pure_quanta
J 0
(8500 3400);
DISPLAY INVISIBLE (8500 3400);
FORCEPROP 1 LAST PART_NUMBER CS24702FB06
J 0
(8450 3500);
DISPLAY 0.510638 (8450 3500);
PAINT WHITE (8450 3500);
DISPLAY INVISIBLE (8450 3500);
FORCEPROP 1 LAST LOCATION R593
J 0
(8150 3400);
DISPLAY 0.702128 (8150 3400);
PAINT YELLOW (8150 3400);
FORCEPROP 0 LAST $SEC 1
J 0
(8225 3450);
DISPLAY INVISIBLE (8225 3450);
FORCEPROP 0 LAST CDS_SEC 1
J 0
(8225 3450);
DISPLAY INVISIBLE (8225 3450);
FORCEPROP 1 LASTPIN (8400 3400) $PN 1
J 0
(8412 3412);
DISPLAY 0.808511 (8412 3412);
PAINT WHITE (8412 3412);
DISPLAY INVISIBLE (8412 3412);
FORCEPROP 1 LASTPIN (8600 3400) $PN 2
J 0
(8562 3412);
DISPLAY 0.808511 (8562 3412);
PAINT WHITE (8562 3412);
DISPLAY INVISIBLE (8562 3412);
FORCEADD OFFPAGE..2
(13700 4200);
FORCEPROP 2 LAST $XR0 35 
J 0
(13889 4200);
DISPLAY 0.638298 (13889 4200);
PAINT MONO (13889 4200);
FORCEPROP 2 LAST PATH I52
J 0
(14000 4250);
DISPLAY 0.680851 (14000 4250);
DISPLAY INVISIBLE (14000 4250);
FORCEPROP 1 LAST COMMENT_BODY TRUE
J 0
(13655 4105);
DISPLAY 0.872340 (13655 4105);
PAINT PEACH (13655 4105);
DISPLAY INVISIBLE (13655 4105);
FORCEPROP 1 LAST OFFPAGE TRUE
J 0
(14025 4075);
DISPLAY 0.872340 (14025 4075);
PAINT GREEN (14025 4075);
DISPLAY INVISIBLE (14025 4075);
FORCEPROP 2 LAST CDS_LIB standard
J 0
(13700 4200);
DISPLAY INVISIBLE (13700 4200);
FORCEADD Q_RES..1
(11950 4200);
FORCEPROP 1 LAST MATERIAL EMPTY
J 0
(12075 4200);
DISPLAY 0.510638 (12075 4200);
PAINT RED (12075 4200);
FORCEPROP 1 LAST VALUE 4.7K
J 2
(11825 4200);
DISPLAY 0.510638 (11825 4200);
PAINT SKYBLUE (11825 4200);
FORCEPROP 1 LAST PACK_TYPE 0402LF
J 0
(12200 4050);
DISPLAY 0.510638 (12200 4050);
PAINT SKYBLUE (12200 4050);
DISPLAY INVISIBLE (12200 4050);
FORCEPROP 1 LAST WATTAGE 1/16W
J 2
(11925 4050);
DISPLAY 0.510638 (11925 4050);
PAINT SKYBLUE (11925 4050);
DISPLAY INVISIBLE (11925 4050);
FORCEPROP 1 LAST PATH I53
J 0
(11900 4350);
DISPLAY 0.978723 (11900 4350);
PAINT WHITE (11900 4350);
DISPLAY INVISIBLE (11900 4350);
FORCEPROP 1 LAST TOLERANCE 1%
J 0
(11950 4100);
DISPLAY 0.510638 (11950 4100);
PAINT SKYBLUE (11950 4100);
DISPLAY INVISIBLE (11950 4100);
FORCEPROP 2 LAST CDS_LIB pure_quanta
J 0
(11950 4200);
DISPLAY INVISIBLE (11950 4200);
FORCEPROP 1 LAST PART_NUMBER CS24702FB06
J 0
(11900 4300);
DISPLAY 0.510638 (11900 4300);
PAINT WHITE (11900 4300);
DISPLAY INVISIBLE (11900 4300);
FORCEPROP 1 LAST LOCATION R641
J 0
(11600 4200);
DISPLAY 0.702128 (11600 4200);
PAINT YELLOW (11600 4200);
FORCEPROP 0 LAST $SEC 1
J 0
(11675 4250);
DISPLAY INVISIBLE (11675 4250);
FORCEPROP 0 LAST CDS_SEC 1
J 0
(11675 4250);
DISPLAY INVISIBLE (11675 4250);
FORCEPROP 1 LASTPIN (11850 4200) $PN 1
J 0
(11862 4212);
DISPLAY 0.808511 (11862 4212);
PAINT WHITE (11862 4212);
DISPLAY INVISIBLE (11862 4212);
FORCEPROP 1 LASTPIN (12050 4200) $PN 2
J 0
(12012 4212);
DISPLAY 0.808511 (12012 4212);
PAINT WHITE (12012 4212);
DISPLAY INVISIBLE (12012 4212);
FORCEADD UNIVERSAL_POWER..1
(11500 4400);
FORCEPROP 3 LASTPIN (11500 4350) SIG_NAME P3V3_AUX\g
J 0
(11510 4360);
DISPLAY 0.659574 (11510 4360);
PAINT MONO (11510 4360);
DISPLAY INVISIBLE (11510 4360);
FORCEPROP 1 LAST HDL_POWER P3V3_AUX
J 1
(11500 4450);
DISPLAY 0.702128 (11500 4450);
PAINT GREEN (11500 4450);
FORCEPROP 1 LAST PATH I54
J 0
(11550 4425);
DISPLAY 0.872340 (11550 4425);
PAINT AQUA (11550 4425);
DISPLAY INVISIBLE (11550 4425);
FORCEPROP 2 LAST CDS_LIB logical_power
J 0
(11500 4400);
DISPLAY INVISIBLE (11500 4400);
FORCEADD OFFPAGE..2
(10225 300);
FORCEPROP 2 LAST $XR0 15 
J 0
(10414 300);
DISPLAY 0.638298 (10414 300);
PAINT MONO (10414 300);
FORCEPROP 2 LAST $XR1 34 
J 0
(10504 300);
DISPLAY 0.638298 (10504 300);
PAINT MONO (10504 300);
FORCEPROP 2 LAST PATH I55
J 0
(10525 350);
DISPLAY 0.680851 (10525 350);
DISPLAY INVISIBLE (10525 350);
FORCEPROP 1 LAST COMMENT_BODY TRUE
J 0
(10180 205);
DISPLAY 0.872340 (10180 205);
PAINT PEACH (10180 205);
DISPLAY INVISIBLE (10180 205);
FORCEPROP 1 LAST OFFPAGE TRUE
J 0
(10550 175);
DISPLAY 0.872340 (10550 175);
PAINT GREEN (10550 175);
DISPLAY INVISIBLE (10550 175);
FORCEPROP 2 LAST CDS_LIB standard
J 0
(10225 300);
DISPLAY INVISIBLE (10225 300);
FORCEADD Q_RES..1
(8475 300);
FORCEPROP 1 LAST VALUE 4.7K
J 2
(8350 300);
DISPLAY 0.510638 (8350 300);
PAINT SKYBLUE (8350 300);
FORCEPROP 1 LAST MATERIAL EMPTY
J 0
(8600 300);
DISPLAY 0.510638 (8600 300);
PAINT RED (8600 300);
FORCEPROP 1 LAST PACK_TYPE 0402LF
J 0
(8725 150);
DISPLAY 0.510638 (8725 150);
PAINT SKYBLUE (8725 150);
DISPLAY INVISIBLE (8725 150);
FORCEPROP 1 LAST WATTAGE 1/16W
J 2
(8450 150);
DISPLAY 0.510638 (8450 150);
PAINT SKYBLUE (8450 150);
DISPLAY INVISIBLE (8450 150);
FORCEPROP 1 LAST PATH I56
J 0
(8425 450);
DISPLAY 0.978723 (8425 450);
PAINT WHITE (8425 450);
DISPLAY INVISIBLE (8425 450);
FORCEPROP 1 LAST TOLERANCE 1%
J 0
(8475 200);
DISPLAY 0.510638 (8475 200);
PAINT SKYBLUE (8475 200);
DISPLAY INVISIBLE (8475 200);
FORCEPROP 2 LAST CDS_LIB pure_quanta
J 0
(8475 300);
DISPLAY INVISIBLE (8475 300);
FORCEPROP 1 LAST PART_NUMBER CS24702FB06
J 0
(8425 400);
DISPLAY 0.510638 (8425 400);
PAINT WHITE (8425 400);
DISPLAY INVISIBLE (8425 400);
FORCEPROP 1 LAST LOCATION R640
J 0
(8125 300);
DISPLAY 0.702128 (8125 300);
PAINT YELLOW (8125 300);
FORCEPROP 0 LAST $SEC 1
J 0
(8200 350);
DISPLAY INVISIBLE (8200 350);
FORCEPROP 0 LAST CDS_SEC 1
J 0
(8200 350);
DISPLAY INVISIBLE (8200 350);
FORCEPROP 1 LASTPIN (8375 300) $PN 1
J 0
(8387 312);
DISPLAY 0.808511 (8387 312);
PAINT WHITE (8387 312);
DISPLAY INVISIBLE (8387 312);
FORCEPROP 1 LASTPIN (8575 300) $PN 2
J 0
(8537 312);
DISPLAY 0.808511 (8537 312);
PAINT WHITE (8537 312);
DISPLAY INVISIBLE (8537 312);
FORCEADD UNIVERSAL_GND..1
(8050 -350);
FORCEPROP 3 LASTPIN (8050 -300) SIG_NAME GND\g
J 0
(8060 -290);
DISPLAY 0.659574 (8060 -290);
PAINT MONO (8060 -290);
DISPLAY INVISIBLE (8060 -290);
FORCEPROP 1 LAST PATH I57
J 0
(8125 -350);
DISPLAY 0.872340 (8125 -350);
PAINT AQUA (8125 -350);
DISPLAY INVISIBLE (8125 -350);
FORCEPROP 1 LAST HDL_POWER GND
J 1
(8075 -425);
DISPLAY 0.702128 (8075 -425);
PAINT GREEN (8075 -425);
DISPLAY INVISIBLE (8075 -425);
FORCEPROP 2 LAST CDS_LIB logical_power
J 0
(8050 -350);
DISPLAY INVISIBLE (8050 -350);
FORCEADD Q_RES..1
(8475 75);
FORCEPROP 1 LAST VALUE 100K
J 2
(8350 75);
DISPLAY 0.510638 (8350 75);
PAINT SKYBLUE (8350 75);
FORCEPROP 1 LAST MATERIAL CHIP
J 0
(8600 75);
DISPLAY 0.510638 (8600 75);
PAINT SKYBLUE (8600 75);
FORCEPROP 1 LAST PACK_TYPE 0402LF
J 0
(8725 -75);
DISPLAY 0.510638 (8725 -75);
PAINT SKYBLUE (8725 -75);
DISPLAY INVISIBLE (8725 -75);
FORCEPROP 1 LAST WATTAGE 1/16W
J 2
(8450 -75);
DISPLAY 0.510638 (8450 -75);
PAINT SKYBLUE (8450 -75);
DISPLAY INVISIBLE (8450 -75);
FORCEPROP 1 LAST PATH I58
J 0
(8425 225);
DISPLAY 0.978723 (8425 225);
PAINT WHITE (8425 225);
DISPLAY INVISIBLE (8425 225);
FORCEPROP 1 LAST TOLERANCE 1%
J 0
(8475 -25);
DISPLAY 0.510638 (8475 -25);
PAINT SKYBLUE (8475 -25);
DISPLAY INVISIBLE (8475 -25);
FORCEPROP 1 LAST PART_NUMBER CS41002FB09
J 0
(8425 175);
DISPLAY 0.510638 (8425 175);
PAINT WHITE (8425 175);
DISPLAY INVISIBLE (8425 175);
FORCEPROP 2 LAST CDS_LIB pure_quanta
J 0
(8475 75);
DISPLAY INVISIBLE (8475 75);
FORCEPROP 1 LAST LOCATION R642
J 0
(8125 75);
DISPLAY 0.702128 (8125 75);
PAINT YELLOW (8125 75);
FORCEPROP 0 LAST $SEC 1
J 0
(8200 125);
DISPLAY INVISIBLE (8200 125);
FORCEPROP 0 LAST CDS_SEC 1
J 0
(8200 125);
DISPLAY INVISIBLE (8200 125);
FORCEPROP 1 LASTPIN (8375 75) $PN 1
J 0
(8387 87);
DISPLAY 0.808511 (8387 87);
PAINT WHITE (8387 87);
DISPLAY INVISIBLE (8387 87);
FORCEPROP 1 LASTPIN (8575 75) $PN 2
J 0
(8537 87);
DISPLAY 0.808511 (8537 87);
PAINT WHITE (8537 87);
DISPLAY INVISIBLE (8537 87);
FORCEADD OFFPAGE..2
(10250 625);
FORCEPROP 2 LAST $XR0 36 
J 0
(10439 625);
DISPLAY 0.638298 (10439 625);
PAINT MONO (10439 625);
FORCEPROP 2 LAST $XR1 13 
J 0
(10529 625);
DISPLAY 0.638298 (10529 625);
PAINT MONO (10529 625);
FORCEPROP 2 LAST $XR2 28 
J 0
(10619 625);
DISPLAY 0.638298 (10619 625);
PAINT MONO (10619 625);
FORCEPROP 2 LAST PATH I6
J 0
(10550 675);
DISPLAY 0.680851 (10550 675);
DISPLAY INVISIBLE (10550 675);
FORCEPROP 1 LAST COMMENT_BODY TRUE
J 0
(10205 530);
DISPLAY 0.872340 (10205 530);
PAINT PEACH (10205 530);
DISPLAY INVISIBLE (10205 530);
FORCEPROP 1 LAST OFFPAGE TRUE
J 0
(10575 500);
DISPLAY 0.872340 (10575 500);
PAINT GREEN (10575 500);
DISPLAY INVISIBLE (10575 500);
FORCEPROP 2 LAST CDS_LIB standard
J 0
(10250 625);
DISPLAY INVISIBLE (10250 625);
FORCEADD OFFPAGE..2
(10250 950);
FORCEPROP 2 LAST $XR0 13 
J 0
(10439 950);
DISPLAY 0.638298 (10439 950);
PAINT MONO (10439 950);
FORCEPROP 2 LAST $XR1 36 
J 0
(10529 950);
DISPLAY 0.638298 (10529 950);
PAINT MONO (10529 950);
FORCEPROP 2 LAST PATH I60
J 0
(10550 1000);
DISPLAY 0.680851 (10550 1000);
DISPLAY INVISIBLE (10550 1000);
FORCEPROP 1 LAST COMMENT_BODY TRUE
J 0
(10205 855);
DISPLAY 0.872340 (10205 855);
PAINT PEACH (10205 855);
DISPLAY INVISIBLE (10205 855);
FORCEPROP 1 LAST OFFPAGE TRUE
J 0
(10575 825);
DISPLAY 0.872340 (10575 825);
PAINT GREEN (10575 825);
DISPLAY INVISIBLE (10575 825);
FORCEPROP 2 LAST CDS_LIB standard
J 0
(10250 950);
DISPLAY INVISIBLE (10250 950);
FORCEADD Q_RES..1
(8500 950);
FORCEPROP 1 LAST MATERIAL CHIP
J 0
(8625 950);
DISPLAY 0.510638 (8625 950);
PAINT SKYBLUE (8625 950);
FORCEPROP 1 LAST VALUE 4.7K
J 2
(8375 950);
DISPLAY 0.510638 (8375 950);
PAINT SKYBLUE (8375 950);
FORCEPROP 1 LAST PACK_TYPE 0402LF
J 0
(8750 800);
DISPLAY 0.510638 (8750 800);
PAINT SKYBLUE (8750 800);
DISPLAY INVISIBLE (8750 800);
FORCEPROP 1 LAST WATTAGE 1/16W
J 2
(8475 800);
DISPLAY 0.510638 (8475 800);
PAINT SKYBLUE (8475 800);
DISPLAY INVISIBLE (8475 800);
FORCEPROP 1 LAST PATH I61
J 0
(8450 1100);
DISPLAY 0.978723 (8450 1100);
PAINT WHITE (8450 1100);
DISPLAY INVISIBLE (8450 1100);
FORCEPROP 1 LAST TOLERANCE 1%
J 0
(8500 850);
DISPLAY 0.510638 (8500 850);
PAINT SKYBLUE (8500 850);
DISPLAY INVISIBLE (8500 850);
FORCEPROP 2 LAST CDS_LIB pure_quanta
J 0
(8500 950);
DISPLAY INVISIBLE (8500 950);
FORCEPROP 1 LAST PART_NUMBER CS24702FB06
J 0
(8450 1050);
DISPLAY 0.510638 (8450 1050);
PAINT WHITE (8450 1050);
DISPLAY INVISIBLE (8450 1050);
FORCEPROP 1 LAST LOCATION R749
J 0
(8150 950);
DISPLAY 0.702128 (8150 950);
PAINT YELLOW (8150 950);
FORCEPROP 0 LAST $SEC 1
J 0
(8225 1000);
DISPLAY INVISIBLE (8225 1000);
FORCEPROP 0 LAST CDS_SEC 1
J 0
(8225 1000);
DISPLAY INVISIBLE (8225 1000);
FORCEPROP 1 LASTPIN (8400 950) $PN 1
J 0
(8412 962);
DISPLAY 0.808511 (8412 962);
PAINT WHITE (8412 962);
DISPLAY INVISIBLE (8412 962);
FORCEPROP 1 LASTPIN (8600 950) $PN 2
J 0
(8562 962);
DISPLAY 0.808511 (8562 962);
PAINT WHITE (8562 962);
DISPLAY INVISIBLE (8562 962);
FORCEADD OFFPAGE..2
(13700 4050);
FORCEPROP 2 LAST $XR1 15 
J 0
(13979 4050);
DISPLAY 0.638298 (13979 4050);
PAINT MONO (13979 4050);
FORCEPROP 2 LAST $XR0 35 
J 0
(13889 4050);
DISPLAY 0.638298 (13889 4050);
PAINT MONO (13889 4050);
FORCEPROP 2 LAST PATH I62
J 0
(13900 4100);
DISPLAY 0.680851 (13900 4100);
DISPLAY INVISIBLE (13900 4100);
FORCEPROP 1 LAST COMMENT_BODY TRUE
J 0
(13655 3955);
DISPLAY 0.872340 (13655 3955);
PAINT PEACH (13655 3955);
DISPLAY INVISIBLE (13655 3955);
FORCEPROP 1 LAST OFFPAGE TRUE
J 0
(14025 3925);
DISPLAY 0.872340 (14025 3925);
PAINT GREEN (14025 3925);
DISPLAY INVISIBLE (14025 3925);
FORCEPROP 2 LAST CDS_LIB standard
J 0
(13700 4050);
DISPLAY INVISIBLE (13700 4050);
FORCEADD Q_RES..1
(11950 4050);
FORCEPROP 1 LAST VALUE 4.7K
J 2
(11825 4050);
DISPLAY 0.510638 (11825 4050);
PAINT SKYBLUE (11825 4050);
FORCEPROP 1 LAST MATERIAL CHIP
J 0
(12075 4050);
DISPLAY 0.510638 (12075 4050);
PAINT SKYBLUE (12075 4050);
FORCEPROP 1 LAST PACK_TYPE 0402LF
J 0
(12200 3900);
DISPLAY 0.510638 (12200 3900);
PAINT SKYBLUE (12200 3900);
DISPLAY INVISIBLE (12200 3900);
FORCEPROP 1 LAST WATTAGE 1/16W
J 2
(11925 3900);
DISPLAY 0.510638 (11925 3900);
PAINT SKYBLUE (11925 3900);
DISPLAY INVISIBLE (11925 3900);
FORCEPROP 1 LAST PATH I63
J 0
(11900 4200);
DISPLAY 0.978723 (11900 4200);
PAINT WHITE (11900 4200);
DISPLAY INVISIBLE (11900 4200);
FORCEPROP 1 LAST TOLERANCE 1%
J 0
(11950 3950);
DISPLAY 0.510638 (11950 3950);
PAINT SKYBLUE (11950 3950);
DISPLAY INVISIBLE (11950 3950);
FORCEPROP 2 LAST CDS_LIB pure_quanta
J 0
(11950 4050);
DISPLAY INVISIBLE (11950 4050);
FORCEPROP 1 LAST PART_NUMBER CS24702FB06
J 0
(11900 4150);
DISPLAY 0.510638 (11900 4150);
PAINT WHITE (11900 4150);
DISPLAY INVISIBLE (11900 4150);
FORCEPROP 1 LAST LOCATION R835
J 0
(11600 4050);
DISPLAY 0.702128 (11600 4050);
PAINT YELLOW (11600 4050);
FORCEPROP 0 LAST $SEC 1
J 0
(11675 4100);
DISPLAY INVISIBLE (11675 4100);
FORCEPROP 0 LAST CDS_SEC 1
J 0
(11675 4100);
DISPLAY INVISIBLE (11675 4100);
FORCEPROP 1 LASTPIN (11850 4050) $PN 1
J 0
(11862 4062);
DISPLAY 0.808511 (11862 4062);
PAINT WHITE (11862 4062);
DISPLAY INVISIBLE (11862 4062);
FORCEPROP 1 LASTPIN (12050 4050) $PN 2
J 0
(12012 4062);
DISPLAY 0.808511 (12012 4062);
PAINT WHITE (12012 4062);
DISPLAY INVISIBLE (12012 4062);
FORCEADD OFFPAGE..2
(10250 3550);
FORCEPROP 2 LAST $XR0 13 
J 0
(10439 3550);
DISPLAY 0.638298 (10439 3550);
PAINT MONO (10439 3550);
FORCEPROP 2 LAST $XR1 49 
J 0
(10529 3550);
DISPLAY 0.638298 (10529 3550);
PAINT MONO (10529 3550);
FORCEPROP 2 LAST CDS_LIB standard
J 0
(10250 3550);
DISPLAY INVISIBLE (10250 3550);
FORCEPROP 2 LAST PATH I64
J 0
(10550 3600);
DISPLAY 0.680851 (10550 3600);
DISPLAY INVISIBLE (10550 3600);
FORCEPROP 1 LAST OFFPAGE TRUE
J 0
(10575 3425);
DISPLAY 0.872340 (10575 3425);
PAINT GREEN (10575 3425);
DISPLAY INVISIBLE (10575 3425);
FORCEPROP 1 LAST COMMENT_BODY TRUE
J 0
(10205 3455);
DISPLAY 0.872340 (10205 3455);
PAINT PEACH (10205 3455);
DISPLAY INVISIBLE (10205 3455);
FORCEADD Q_RES..1
(8500 3550);
FORCEPROP 1 LAST MATERIAL CHIP
J 0
(8625 3550);
DISPLAY 0.510638 (8625 3550);
PAINT SKYBLUE (8625 3550);
FORCEPROP 1 LAST VALUE 4.7K
J 2
(8375 3550);
DISPLAY 0.510638 (8375 3550);
PAINT SKYBLUE (8375 3550);
FORCEPROP 2 LAST CDS_LIB pure_quanta
J 0
(8500 3550);
DISPLAY INVISIBLE (8500 3550);
FORCEPROP 1 LAST PATH I65
J 0
(8450 3700);
DISPLAY 0.978723 (8450 3700);
PAINT WHITE (8450 3700);
DISPLAY INVISIBLE (8450 3700);
FORCEPROP 1 LAST PART_NUMBER CS24702FB06
J 0
(8450 3650);
DISPLAY 0.510638 (8450 3650);
PAINT WHITE (8450 3650);
DISPLAY INVISIBLE (8450 3650);
FORCEPROP 1 LAST TOLERANCE 1%
J 0
(8500 3450);
DISPLAY 0.510638 (8500 3450);
PAINT SKYBLUE (8500 3450);
DISPLAY INVISIBLE (8500 3450);
FORCEPROP 1 LAST WATTAGE 1/16W
J 2
(8475 3400);
DISPLAY 0.510638 (8475 3400);
PAINT SKYBLUE (8475 3400);
DISPLAY INVISIBLE (8475 3400);
FORCEPROP 1 LAST PACK_TYPE 0402LF
J 0
(8750 3400);
DISPLAY 0.510638 (8750 3400);
PAINT SKYBLUE (8750 3400);
DISPLAY INVISIBLE (8750 3400);
FORCEPROP 1 LAST $LOCATION R319
J 0
(8150 3550);
DISPLAY 0.702128 (8150 3550);
PAINT YELLOW (8150 3550);
FORCEPROP 0 LAST CDS_LOCATION R319
J 0
(8150 3600);
DISPLAY 0.680851 (8150 3600);
DISPLAY INVISIBLE (8150 3600);
FORCEPROP 0 LAST $SEC 1
J 0
(8225 3600);
DISPLAY INVISIBLE (8225 3600);
FORCEPROP 0 LAST CDS_SEC 1
J 0
(8225 3600);
DISPLAY INVISIBLE (8225 3600);
FORCEPROP 1 LASTPIN (8400 3550) $PN 1
J 0
(8412 3562);
DISPLAY 0.808511 (8412 3562);
PAINT WHITE (8412 3562);
DISPLAY INVISIBLE (8412 3562);
FORCEPROP 1 LASTPIN (8600 3550) $PN 2
J 0
(8562 3562);
DISPLAY 0.808511 (8562 3562);
PAINT WHITE (8562 3562);
DISPLAY INVISIBLE (8562 3562);
FORCEADD OFFPAGE..2
(10250 4300);
FORCEPROP 2 LAST $XR0 13 
J 0
(10439 4300);
DISPLAY 0.638298 (10439 4300);
PAINT MONO (10439 4300);
FORCEPROP 2 LAST $XR1 34 
J 0
(10529 4300);
DISPLAY 0.638298 (10529 4300);
PAINT MONO (10529 4300);
FORCEPROP 2 LAST $XR2 31 
J 0
(10619 4300);
DISPLAY 0.638298 (10619 4300);
PAINT MONO (10619 4300);
FORCEPROP 1 LAST COMMENT_BODY TRUE
J 0
(10205 4205);
DISPLAY 0.872340 (10205 4205);
PAINT PEACH (10205 4205);
DISPLAY INVISIBLE (10205 4205);
FORCEPROP 1 LAST OFFPAGE TRUE
J 0
(10575 4175);
DISPLAY 0.872340 (10575 4175);
PAINT GREEN (10575 4175);
DISPLAY INVISIBLE (10575 4175);
FORCEPROP 2 LAST PATH I66
J 0
(10425 4375);
DISPLAY 0.680851 (10425 4375);
DISPLAY INVISIBLE (10425 4375);
FORCEPROP 2 LAST CDS_LIB standard
J 0
(10250 4300);
DISPLAY INVISIBLE (10250 4300);
FORCEADD Q_RES..1
(8500 4300);
FORCEPROP 1 LAST VALUE 4.7K
J 2
(8375 4300);
DISPLAY 0.510638 (8375 4300);
PAINT SKYBLUE (8375 4300);
FORCEPROP 1 LAST MATERIAL CHIP
J 0
(8625 4300);
DISPLAY 0.510638 (8625 4300);
PAINT SKYBLUE (8625 4300);
FORCEPROP 1 LAST PACK_TYPE 0402LF
J 0
(8750 4150);
DISPLAY 0.510638 (8750 4150);
PAINT SKYBLUE (8750 4150);
DISPLAY INVISIBLE (8750 4150);
FORCEPROP 1 LAST WATTAGE 1/16W
J 2
(8475 4150);
DISPLAY 0.510638 (8475 4150);
PAINT SKYBLUE (8475 4150);
DISPLAY INVISIBLE (8475 4150);
FORCEPROP 1 LAST TOLERANCE 1%
J 0
(8500 4200);
DISPLAY 0.510638 (8500 4200);
PAINT SKYBLUE (8500 4200);
DISPLAY INVISIBLE (8500 4200);
FORCEPROP 1 LAST PART_NUMBER CS24702FB06
J 0
(8450 4400);
DISPLAY 0.510638 (8450 4400);
PAINT WHITE (8450 4400);
DISPLAY INVISIBLE (8450 4400);
FORCEPROP 1 LAST PATH I67
J 0
(8450 4450);
DISPLAY 0.978723 (8450 4450);
PAINT WHITE (8450 4450);
DISPLAY INVISIBLE (8450 4450);
FORCEPROP 2 LAST CDS_LIB pure_quanta
J 0
(8500 4300);
DISPLAY INVISIBLE (8500 4300);
FORCEPROP 1 LAST LOCATION R586
J 0
(8450 4350);
DISPLAY 0.978723 (8450 4350);
FORCEPROP 1 LASTPIN (8400 4300) $PN 1
J 0
(8412 4312);
DISPLAY 0.787234 (8412 4312);
PAINT MONO (8412 4312);
FORCEPROP 1 LASTPIN (8600 4300) $PN 2
J 0
(8562 4312);
DISPLAY 0.787234 (8562 4312);
PAINT MONO (8562 4312);
FORCEPROP 0 LAST $SEC 1
J 0
(8450 4400);
DISPLAY 0.680851 (8450 4400);
PAINT MONO (8450 4400);
DISPLAY INVISIBLE (8450 4400);
FORCEPROP 0 LAST CDS_SEC 1
J 0
(8450 4400);
DISPLAY 0.680851 (8450 4400);
DISPLAY INVISIBLE (8450 4400);
FORCEADD Q_RES..1
(8500 625);
FORCEPROP 1 LAST MATERIAL CHIP
J 0
(8625 625);
DISPLAY 0.510638 (8625 625);
PAINT SKYBLUE (8625 625);
FORCEPROP 1 LAST VALUE 4.7K
J 2
(8375 625);
DISPLAY 0.510638 (8375 625);
PAINT SKYBLUE (8375 625);
FORCEPROP 1 LAST PACK_TYPE 0402LF
J 0
(8750 475);
DISPLAY 0.510638 (8750 475);
PAINT SKYBLUE (8750 475);
DISPLAY INVISIBLE (8750 475);
FORCEPROP 1 LAST WATTAGE 1/16W
J 2
(8475 475);
DISPLAY 0.510638 (8475 475);
PAINT SKYBLUE (8475 475);
DISPLAY INVISIBLE (8475 475);
FORCEPROP 1 LAST PATH I7
J 0
(8450 775);
DISPLAY 0.978723 (8450 775);
PAINT WHITE (8450 775);
DISPLAY INVISIBLE (8450 775);
FORCEPROP 1 LAST TOLERANCE 1%
J 0
(8500 525);
DISPLAY 0.510638 (8500 525);
PAINT SKYBLUE (8500 525);
DISPLAY INVISIBLE (8500 525);
FORCEPROP 2 LAST CDS_LIB pure_quanta
J 0
(8500 625);
DISPLAY INVISIBLE (8500 625);
FORCEPROP 1 LAST PART_NUMBER CS24702FB06
J 0
(8450 725);
DISPLAY 0.510638 (8450 725);
PAINT WHITE (8450 725);
DISPLAY INVISIBLE (8450 725);
FORCEPROP 1 LAST LOCATION R627
J 0
(8150 625);
DISPLAY 0.702128 (8150 625);
PAINT YELLOW (8150 625);
FORCEPROP 0 LAST $SEC 1
J 0
(8225 675);
DISPLAY INVISIBLE (8225 675);
FORCEPROP 0 LAST CDS_SEC 1
J 0
(8225 675);
DISPLAY INVISIBLE (8225 675);
FORCEPROP 1 LASTPIN (8400 625) $PN 1
J 0
(8412 637);
DISPLAY 0.808511 (8412 637);
PAINT WHITE (8412 637);
DISPLAY INVISIBLE (8412 637);
FORCEPROP 1 LASTPIN (8600 625) $PN 2
J 0
(8562 637);
DISPLAY 0.808511 (8562 637);
PAINT WHITE (8562 637);
DISPLAY INVISIBLE (8562 637);
FORCEADD QUANTA_TITLE_BLOCK_C..1
(16650 -1750);
FORCEPROP 0 LAST CDS_CON_LAST_MODIFIED Fri Aug 25 17:25:45 2023
J 0
(14765 -1735);
DISPLAY INVISIBLE (14765 -1735);
FORCEPROP 2 LAST Q_DEPT 
J 1
(12887 -1701);
DISPLAY 1.957447 (12887 -1701);
PAINT GREEN (12887 -1701);
FORCEPROP 1 LAST CUSTOM_TXT_CDS <CON_LAST_MODIFIED>
J 0
(14765 -1735);
DISPLAY 0.978723 (14765 -1735);
FORCEPROP 2 LAST CUSTOM_TXT_CDS <XR_PAGE_TITLE>
J 0
(8760 3500);
DISPLAY 0.638298 (8760 3500);
PAINT PINK (8760 3500);
DISPLAY INVISIBLE (8760 3500);
FORCEPROP 1 LAST CUSTOM_TXT_CDS <NAME_2>
J 0
(13475 -1700);
FORCEPROP 1 LAST CUSTOM_TXT_CDS <NAME_1>
J 0
(13475 -1575);
FORCEPROP 1 LAST CUSTOM_TXT_CDS <Q_NUMBER>
J 0
(15247 -1647);
DISPLAY 1.212766 (15247 -1647);
FORCEPROP 1 LAST CUSTOM_TXT_CDS <Q_PROJ>
J 0
(14268 -1648);
DISPLAY 1.212766 (14268 -1648);
FORCEPROP 1 LAST CUSTOM_TXT_CDS <Q_REV>
J 0
(16466 -1647);
DISPLAY 1.212766 (16466 -1647);
FORCEPROP 1 LAST CUSTOM_TXT_CDS <CON_PAGE_NUM> OF <CON_TOTAL_PAGES>
J 0
(16204 -1732);
DISPLAY 0.978723 (16204 -1732);
FORCEPROP 1 LAST Q_TITLE BMC/FPGA GPIO PU
J 0
(7384 -1649);
DISPLAY 2.446809 (7384 -1649);
PAINT GREEN (7384 -1649);
FORCEPROP 2 LAST CDS_XR_PAGE_TITLE CR-42 : @SCM_LIB.SCM(SCH_1):PAGE42
J 0
(8760 3500);
DISPLAY 0.638298 (8760 3500);
PAINT PINK (8760 3500);
DISPLAY INVISIBLE (8760 3500);
FORCEPROP 1 LAST COMMENT_BODY TRUE
J 0
(16662 -1763);
DISPLAY 0.978723 (16662 -1763);
PAINT PEACH (16662 -1763);
DISPLAY INVISIBLE (16662 -1763);
FORCEPROP 2 LAST CDS_LIB pure_quanta
J 0
(16650 -1750);
DISPLAY INVISIBLE (16650 -1750);
FORCEPROP 1 LAST CDS_LMAN_SYM_OUTLINE -9475,6775,100,-125
J 0
(16650 -1750);
DISPLAY 0.468085 (16650 -1750);
PAINT GREEN (16650 -1750);
DISPLAY INVISIBLE (16650 -1750);
FORCEPROP 2 LAST PAGE_BORDER TRUE
J 0
(8760 3500);
DISPLAY 0.638298 (8760 3500);
PAINT PINK (8760 3500);
DISPLAY INVISIBLE (8760 3500);
FORCEADD DNS..2
(8500 3225);
PAINT RED (8500 3225);
FORCEPROP 2 LAST CDS_LIB mstr_misc
J 0
(8500 3225);
DISPLAY INVISIBLE (8500 3225);
FORCEPROP 1 LAST COMMENT_BODY TRUE
R 1
J 0
(8575 3000);
DISPLAY 0.872340 (8575 3000);
PAINT PEACH (8575 3000);
DISPLAY INVISIBLE (8575 3000);
FORCEADD DNS..2
(8500 275);
PAINT RED (8500 275);
FORCEPROP 1 LAST COMMENT_BODY TRUE
R 1
J 0
(8575 50);
DISPLAY 0.872340 (8575 50);
PAINT PEACH (8575 50);
DISPLAY INVISIBLE (8575 50);
FORCEPROP 2 LAST CDS_LIB mstr_misc
J 0
(8500 275);
DISPLAY INVISIBLE (8500 275);
FORCEADD DNS..2
(11925 4225);
PAINT RED (11925 4225);
FORCEPROP 1 LAST COMMENT_BODY TRUE
R 1
J 0
(12000 4000);
DISPLAY 0.872340 (12000 4000);
PAINT PEACH (12000 4000);
DISPLAY INVISIBLE (12000 4000);
FORCEPROP 2 LAST CDS_LIB mstr_misc
J 0
(11925 4225);
DISPLAY INVISIBLE (11925 4225);
FORCEADD DNS..2
(8500 3375);
PAINT RED (8500 3375);
FORCEPROP 1 LAST COMMENT_BODY TRUE
R 1
J 0
(8575 3150);
DISPLAY 0.872340 (8575 3150);
PAINT PEACH (8575 3150);
DISPLAY INVISIBLE (8575 3150);
FORCEPROP 2 LAST CDS_LIB mstr_misc
J 0
(8500 3375);
DISPLAY INVISIBLE (8500 3375);
WIRE 16 -1 (11500 4200)(11500 4350);
WIRE 16 -1 (11850 4200)(11500 4200);
WIRE 16 -1 (11500 4050)(11500 4200);
WIRE 16 -1 (8050 4300)(8050 4400);
WIRE 16 -1 (8400 4300)(8050 4300);
WIRE 16 -1 (8050 3550)(8050 4300);
WIRE 16 -1 (8050 -300)(8050 75);
WIRE 16 -1 (11850 4050)(11500 4050);
WIRE 16 -1 (13650 4050)(12050 4050);
FORCEPROP 2 LAST SIG_NAME FM_ADR_TRIGGER_N
J 0
(12440 4060);
DISPLAY 0.808511 (12440 4060);
WIRE 16 -1 (8575 75)(9875 75);
WIRE 16 -1 (9875 300)(8575 300);
FORCEPROP 2 LAST SIG_NAME FM_JTAG_BMC_MUX_SEL
J 0
(9015 310);
DISPLAY 0.851064 (9015 310);
WIRE 16 -1 (9875 75)(9875 300);
WIRE 16 -1 (10175 300)(9875 300);
WIRE 16 -1 (10200 625)(8600 625);
FORCEPROP 2 LAST SIG_NAME PWRGD_DSW_PWROK
J 0
(9015 635);
DISPLAY 0.851064 (9015 635);
WIRE 16 -1 (10200 950)(8600 950);
FORCEPROP 2 LAST SIG_NAME FM_BMC_CRASHLOG_TRIG_N
J 2
(9840 960);
DISPLAY 0.808511 (9840 960);
WIRE 16 -1 (10200 1450)(8600 1450);
FORCEPROP 2 LAST SIG_NAME FM_P12V_HSC_ENABLE
J 0
(9015 1460);
DISPLAY 0.808511 (9015 1460);
WIRE 16 -1 (10200 2500)(8600 2500);
FORCEPROP 2 LAST SIG_NAME BMC_CPLD_GPIO_13
J 2
(9615 2510);
DISPLAY 0.808511 (9615 2510);
WIRE 16 -1 (10200 2650)(8600 2650);
FORCEPROP 2 LAST SIG_NAME BMC_CPLD_GPIO_12
J 2
(9615 2660);
DISPLAY 0.808511 (9615 2660);
WIRE 16 -1 (10200 3250)(8600 3250);
FORCEPROP 2 LAST SIG_NAME BMC_CPLD_GPIO_8
J 2
(9565 3260);
DISPLAY 0.808511 (9565 3260);
WIRE 16 -1 (10200 3400)(8600 3400);
FORCEPROP 2 LAST SIG_NAME BMC_CPLD_GPIO_7
J 2
(9565 3410);
DISPLAY 0.808511 (9565 3410);
WIRE 16 -1 (10200 3550)(8600 3550);
FORCEPROP 2 LAST SIG_NAME BMC_ID_BEEP_SEL
J 2
(9565 3560);
DISPLAY 0.808511 (9565 3560);
WIRE 16 -1 (10200 4300)(8600 4300);
FORCEPROP 2 LAST SIG_NAME BMC_CPLD_GPIO_2
J 0
(8990 4310);
DISPLAY 0.851064 (8990 4310);
WIRE 16 -1 (8400 3550)(8050 3550);
WIRE 16 -1 (8050 3400)(8050 3550);
WIRE 16 -1 (8400 3400)(8050 3400);
WIRE 16 -1 (8050 3250)(8050 3400);
WIRE 16 -1 (8400 3250)(8050 3250);
WIRE 16 -1 (8050 3250)(8050 2650);
WIRE 16 -1 (8400 2650)(8050 2650);
WIRE 16 -1 (8050 2500)(8050 2650);
WIRE 16 -1 (8400 2500)(8050 2500);
WIRE 16 -1 (8050 2500)(8050 1450);
WIRE 16 -1 (8400 1450)(8050 1450);
WIRE 16 -1 (8050 1450)(8050 950);
WIRE 16 -1 (8400 950)(8050 950);
WIRE 16 -1 (8050 950)(8050 625);
WIRE 16 -1 (8400 625)(8050 625);
WIRE 16 -1 (8050 300)(8050 625);
WIRE 16 -1 (8375 300)(8050 300);
WIRE 16 -1 (8050 75)(8375 75);
WIRE 16 -1 (13650 4200)(12050 4200);
FORCEPROP 2 LAST SIG_NAME RST_BMC_SELF_HW_R2
J 0
(12440 4210);
DISPLAY 0.851064 (12440 4210);
DOT 1 (8050 4300);
DOT 1 (8050 3550);
DOT 1 (11500 4200);
DOT 1 (8050 2650);
DOT 1 (8050 3250);
DOT 1 (8050 3400);
DOT 1 (9875 300);
DOT 1 (8050 625);
DOT 1 (8050 950);
DOT 1 (8050 1450);
DOT 1 (8050 2500);
FORCENOTE
FM_JTAG_BMC_MUX_SEL == HIGH , BMC TO CPU/PCH.
(8650 -425) 0;
DISPLAY LEFT (8650 -425);
DISPLAY 1.021277 (8650 -425);
PAINT RED (8650 -425);
FORCENOTE
FM_JTAG_BMC_MUX_SEL == LOW (DEFAULT) , BMC TO CPLD.
(8650 -325) 0;
DISPLAY LEFT (8650 -325);
DISPLAY 1.021277 (8650 -325);
PAINT RED (8650 -325);
FORCENOTE
DESIGN NOTE:
(8650 -200) 0;
DISPLAY LEFT (8650 -200);
DISPLAY 1.021277 (8650 -200);
PAINT RED (8650 -200);
QUIT
